(kicad_pcb
	(version 20260206)
	(generator "pcbnew")
	(generator_version "10.0")
	(general
		(thickness 1.6)
		(legacy_teardrops no)
	)
	(paper "A4")
	(title_block
		(title "04192023_DAF0TMB3IC0_F0TG_MB_C_brd_V02_OCP.brd")
		(comment 1 "Grand Teton / footprints 7096-7101 of 8354")
	)
	(layers
		(0 "F.Cu" signal "TOP")
		(4 "In1.Cu" signal "GND")
		(6 "In2.Cu" signal "IN1")
		(8 "In3.Cu" signal "GND1")
		(10 "In4.Cu" signal "IN2")
		(12 "In5.Cu" signal "GND2")
		(14 "In6.Cu" signal "IN3")
		(16 "In7.Cu" signal "GND3")
		(18 "In8.Cu" signal "VCC")
		(20 "In9.Cu" signal "VCC1")
		(22 "In10.Cu" signal "GND4")
		(24 "In11.Cu" signal "IN4")
		(26 "In12.Cu" signal "GND5")
		(28 "In13.Cu" signal "IN5")
		(30 "In14.Cu" signal "GND6")
		(32 "In15.Cu" signal "IN6")
		(34 "In16.Cu" signal "GND7")
		(2 "B.Cu" signal "BOTTOM")
		(9 "F.Adhes" user "F.Adhesive")
		(11 "B.Adhes" user "B.Adhesive")
		(13 "F.Paste" user "Package Geometry/Pastemask Top")
		(15 "B.Paste" user "Package Geometry/Pastemask Bottom")
		(5 "F.SilkS" user "Ref Des/Silkscreen Top")
		(7 "B.SilkS" user "Ref Des/Silkscreen Bottom")
		(1 "F.Mask" user "Board Geometry/Soldermask Top")
		(3 "B.Mask" user "Board Geometry/Soldermask Bottom")
		(17 "Dwgs.User" user "User.Drawings")
		(19 "Cmts.User" user "User.Comments")
		(21 "Eco1.User" user "User.Eco1")
		(23 "Eco2.User" user "User.Eco2")
		(25 "Edge.Cuts" user "Board Geometry/Outline")
		(27 "Margin" user)
		(31 "F.CrtYd" user "Package Geometry/Place Bound Top")
		(29 "B.CrtYd" user "Package Geometry/Place Bound Bottom")
		(35 "F.Fab" user "Ref Des/Assembly Top")
		(33 "B.Fab" user "Ref Des/Assembly Bottom")
	)
	(footprint ""
		(layer "B.Cu")
		(at 174.317914 -13.762228 -90)
		(property "Reference" "R332"
			(at 0 0 90)
			(layer "B.SilkS")
			(hide yes)
			(effects
				(font
					(size 1.27 1.27)
				)
				(justify mirror)
			)
		)
		(property "Value" ""
			(at 0 0 90)
			(layer "B.Fab")
			(effects
				(font
					(size 1.27 1.27)
				)
				(justify mirror)
			)
		)
		(duplicate_pad_numbers_are_jumpers no)
		(fp_line
			(start -0.7874 0.4064)
			(end 0.7874 0.4064)
			(stroke
				(width 0.1524)
				(type default)
			)
			(layer "B.SilkS")
		)
		(fp_line
			(start 0.7874 0.4064)
			(end 0.7874 -0.4064)
			(stroke
				(width 0.1524)
				(type default)
			)
			(layer "B.SilkS")
		)
		(fp_line
			(start -0.7874 -0.4064)
			(end -0.7874 0.4064)
			(stroke
				(width 0.1524)
				(type default)
			)
			(layer "B.SilkS")
		)
		(fp_line
			(start 0.7874 -0.4064)
			(end -0.7874 -0.4064)
			(stroke
				(width 0.1524)
				(type default)
			)
			(layer "B.SilkS")
		)
		(fp_line
			(start -0.67945 0.3048)
			(end -0.120396 0.3048)
			(stroke
				(width 0.1)
				(type default)
			)
			(layer "B.Fab")
		)
		(fp_line
			(start -0.120396 0.3048)
			(end -0.120396 0.2794)
			(stroke
				(width 0.1)
				(type default)
			)
			(layer "B.Fab")
		)
		(fp_line
			(start 0.12065 0.3048)
			(end 0.67945 0.3048)
			(stroke
				(width 0.1)
				(type default)
			)
			(layer "B.Fab")
		)
		(fp_line
			(start 0.67945 0.3048)
			(end 0.67945 -0.305054)
			(stroke
				(width 0.1)
				(type default)
			)
			(layer "B.Fab")
		)
		(fp_line
			(start -0.120396 0.2794)
			(end 0.12065 0.2794)
			(stroke
				(width 0.1)
				(type default)
			)
			(layer "B.Fab")
		)
		(fp_line
			(start 0.12065 0.2794)
			(end 0.12065 0.3048)
			(stroke
				(width 0.1)
				(type default)
			)
			(layer "B.Fab")
		)
		(fp_line
			(start -0.12065 -0.2794)
			(end -0.12065 -0.3048)
			(stroke
				(width 0.1)
				(type default)
			)
			(layer "B.Fab")
		)
		(fp_line
			(start 0.12065 -0.2794)
			(end -0.12065 -0.2794)
			(stroke
				(width 0.1)
				(type default)
			)
			(layer "B.Fab")
		)
		(fp_line
			(start -0.67945 -0.3048)
			(end -0.67945 0.3048)
			(stroke
				(width 0.1)
				(type default)
			)
			(layer "B.Fab")
		)
		(fp_line
			(start -0.12065 -0.3048)
			(end -0.67945 -0.3048)
			(stroke
				(width 0.1)
				(type default)
			)
			(layer "B.Fab")
		)
		(fp_line
			(start 0.12065 -0.305054)
			(end 0.12065 -0.2794)
			(stroke
				(width 0.1)
				(type default)
			)
			(layer "B.Fab")
		)
		(fp_line
			(start 0.67945 -0.305054)
			(end 0.12065 -0.305054)
			(stroke
				(width 0.1)
				(type default)
			)
			(layer "B.Fab")
		)
		(pad "1" smd circle
			(at 0.40005 0 90)
			(size 0 0)
			(layers "B.Cu" "B.Mask" "B.Paste")
			(net "I3C_BMC_SWB_SCL")
		)
		(pad "2" smd circle
			(at -0.40005 0 90)
			(size 0 0)
			(layers "B.Cu" "B.Mask" "B.Paste")
			(net "P3V3_AUX")
		)
	)
	(footprint ""
		(layer "B.Cu")
		(at 231.872536 -326.07885 180)
		(property "Reference" "R1250"
			(at 0 0 0)
			(layer "B.SilkS")
			(hide yes)
			(effects
				(font
					(size 1.27 1.27)
				)
				(justify mirror)
			)
		)
		(property "Value" ""
			(at 0 0 0)
			(layer "B.Fab")
			(effects
				(font
					(size 1.27 1.27)
				)
				(justify mirror)
			)
		)
		(duplicate_pad_numbers_are_jumpers no)
		(fp_line
			(start 0.7874 0.4064)
			(end 0.7874 -0.4064)
			(stroke
				(width 0.1524)
				(type default)
			)
			(layer "B.SilkS")
		)
		(fp_line
			(start 0.7874 -0.4064)
			(end -0.7874 -0.4064)
			(stroke
				(width 0.1524)
				(type default)
			)
			(layer "B.SilkS")
		)
		(fp_line
			(start -0.7874 0.4064)
			(end 0.7874 0.4064)
			(stroke
				(width 0.1524)
				(type default)
			)
			(layer "B.SilkS")
		)
		(fp_line
			(start -0.7874 -0.4064)
			(end -0.7874 0.4064)
			(stroke
				(width 0.1524)
				(type default)
			)
			(layer "B.SilkS")
		)
		(fp_line
			(start 0.67945 0.3048)
			(end 0.67945 -0.305054)
			(stroke
				(width 0.1)
				(type default)
			)
			(layer "B.Fab")
		)
		(fp_line
			(start 0.67945 -0.305054)
			(end 0.12065 -0.305054)
			(stroke
				(width 0.1)
				(type default)
			)
			(layer "B.Fab")
		)
		(fp_line
			(start 0.12065 0.3048)
			(end 0.67945 0.3048)
			(stroke
				(width 0.1)
				(type default)
			)
			(layer "B.Fab")
		)
		(fp_line
			(start 0.12065 0.2794)
			(end 0.12065 0.3048)
			(stroke
				(width 0.1)
				(type default)
			)
			(layer "B.Fab")
		)
		(fp_line
			(start 0.12065 -0.2794)
			(end -0.12065 -0.2794)
			(stroke
				(width 0.1)
				(type default)
			)
			(layer "B.Fab")
		)
		(fp_line
			(start 0.12065 -0.305054)
			(end 0.12065 -0.2794)
			(stroke
				(width 0.1)
				(type default)
			)
			(layer "B.Fab")
		)
		(fp_line
			(start -0.120396 0.3048)
			(end -0.120396 0.2794)
			(stroke
				(width 0.1)
				(type default)
			)
			(layer "B.Fab")
		)
		(fp_line
			(start -0.120396 0.2794)
			(end 0.12065 0.2794)
			(stroke
				(width 0.1)
				(type default)
			)
			(layer "B.Fab")
		)
		(fp_line
			(start -0.12065 -0.2794)
			(end -0.12065 -0.3048)
			(stroke
				(width 0.1)
				(type default)
			)
			(layer "B.Fab")
		)
		(fp_line
			(start -0.12065 -0.3048)
			(end -0.67945 -0.3048)
			(stroke
				(width 0.1)
				(type default)
			)
			(layer "B.Fab")
		)
		(fp_line
			(start -0.67945 0.3048)
			(end -0.120396 0.3048)
			(stroke
				(width 0.1)
				(type default)
			)
			(layer "B.Fab")
		)
		(fp_line
			(start -0.67945 -0.3048)
			(end -0.67945 0.3048)
			(stroke
				(width 0.1)
				(type default)
			)
			(layer "B.Fab")
		)
		(pad "1" smd rect
			(at 0.40005 0 180)
			(size 0.4572 0.508)
			(layers "B.Cu" "B.Mask" "B.Paste")
			(net "P1V8_CPU1_RT_1D_ADC")
		)
		(pad "2" smd rect
			(at -0.40005 0 180)
			(size 0.4572 0.508)
			(layers "B.Cu" "B.Mask" "B.Paste")
			(net "P1V8_CPU1_RT_1D_ADC_MAM")
		)
	)
	(footprint ""
		(layer "B.Cu")
		(at 154.00782 -13.762228 90)
		(property "Reference" "R2415"
			(at 0 0 90)
			(layer "B.SilkS")
			(hide yes)
			(effects
				(font
					(size 1.27 1.27)
				)
				(justify mirror)
			)
		)
		(property "Value" ""
			(at 0 0 90)
			(layer "B.Fab")
			(effects
				(font
					(size 1.27 1.27)
				)
				(justify mirror)
			)
		)
		(duplicate_pad_numbers_are_jumpers no)
		(fp_line
			(start 0.7874 -0.4064)
			(end -0.7874 -0.4064)
			(stroke
				(width 0.1524)
				(type default)
			)
			(layer "B.SilkS")
		)
		(fp_line
			(start -0.7874 -0.4064)
			(end -0.7874 0.4064)
			(stroke
				(width 0.1524)
				(type default)
			)
			(layer "B.SilkS")
		)
		(fp_line
			(start 0.7874 0.4064)
			(end 0.7874 -0.4064)
			(stroke
				(width 0.1524)
				(type default)
			)
			(layer "B.SilkS")
		)
		(fp_line
			(start -0.7874 0.4064)
			(end 0.7874 0.4064)
			(stroke
				(width 0.1524)
				(type default)
			)
			(layer "B.SilkS")
		)
		(fp_line
			(start 0.67945 -0.305054)
			(end 0.12065 -0.305054)
			(stroke
				(width 0.1)
				(type default)
			)
			(layer "B.Fab")
		)
		(fp_line
			(start 0.12065 -0.305054)
			(end 0.12065 -0.2794)
			(stroke
				(width 0.1)
				(type default)
			)
			(layer "B.Fab")
		)
		(fp_line
			(start -0.12065 -0.3048)
			(end -0.67945 -0.3048)
			(stroke
				(width 0.1)
				(type default)
			)
			(layer "B.Fab")
		)
		(fp_line
			(start -0.67945 -0.3048)
			(end -0.67945 0.3048)
			(stroke
				(width 0.1)
				(type default)
			)
			(layer "B.Fab")
		)
		(fp_line
			(start 0.12065 -0.2794)
			(end -0.12065 -0.2794)
			(stroke
				(width 0.1)
				(type default)
			)
			(layer "B.Fab")
		)
		(fp_line
			(start -0.12065 -0.2794)
			(end -0.12065 -0.3048)
			(stroke
				(width 0.1)
				(type default)
			)
			(layer "B.Fab")
		)
		(fp_line
			(start 0.12065 0.2794)
			(end 0.12065 0.3048)
			(stroke
				(width 0.1)
				(type default)
			)
			(layer "B.Fab")
		)
		(fp_line
			(start -0.120396 0.2794)
			(end 0.12065 0.2794)
			(stroke
				(width 0.1)
				(type default)
			)
			(layer "B.Fab")
		)
		(fp_line
			(start 0.67945 0.3048)
			(end 0.67945 -0.305054)
			(stroke
				(width 0.1)
				(type default)
			)
			(layer "B.Fab")
		)
		(fp_line
			(start 0.12065 0.3048)
			(end 0.67945 0.3048)
			(stroke
				(width 0.1)
				(type default)
			)
			(layer "B.Fab")
		)
		(fp_line
			(start -0.120396 0.3048)
			(end -0.120396 0.2794)
			(stroke
				(width 0.1)
				(type default)
			)
			(layer "B.Fab")
		)
		(fp_line
			(start -0.67945 0.3048)
			(end -0.120396 0.3048)
			(stroke
				(width 0.1)
				(type default)
			)
			(layer "B.Fab")
		)
		(pad "1" smd circle
			(at 0.40005 0 270)
			(size 0 0)
			(layers "B.Cu" "B.Mask" "B.Paste")
			(net "SMB_1_BMC_GPU_SCL")
		)
		(pad "2" smd circle
			(at -0.40005 0 270)
			(size 0 0)
			(layers "B.Cu" "B.Mask" "B.Paste")
			(net "SMB_PCIE3_3V3AUX_SCL_R")
		)
	)
	(footprint ""
		(layer "B.Cu")
		(at 111.477044 -261.748016 90)
		(property "Reference" "C2291"
			(at 0 0 90)
			(layer "B.SilkS")
			(hide yes)
			(effects
				(font
					(size 1.27 1.27)
				)
				(justify mirror)
			)
		)
		(property "Value" ""
			(at 0 0 90)
			(layer "B.Fab")
			(effects
				(font
					(size 1.27 1.27)
				)
				(justify mirror)
			)
		)
		(duplicate_pad_numbers_are_jumpers no)
		(fp_line
			(start 0.7874 -0.4064)
			(end -0.7874 -0.4064)
			(stroke
				(width 0.1524)
				(type default)
			)
			(layer "B.SilkS")
		)
		(fp_line
			(start -0.7874 -0.4064)
			(end -0.7874 0.4064)
			(stroke
				(width 0.1524)
				(type default)
			)
			(layer "B.SilkS")
		)
		(fp_line
			(start 0.7874 0.4064)
			(end 0.7874 -0.4064)
			(stroke
				(width 0.1524)
				(type default)
			)
			(layer "B.SilkS")
		)
		(fp_line
			(start -0.7874 0.4064)
			(end 0.7874 0.4064)
			(stroke
				(width 0.1524)
				(type default)
			)
			(layer "B.SilkS")
		)
		(fp_line
			(start 0.67945 -0.305054)
			(end 0.12065 -0.305054)
			(stroke
				(width 0.1)
				(type default)
			)
			(layer "B.Fab")
		)
		(fp_line
			(start 0.12065 -0.305054)
			(end 0.12065 -0.2794)
			(stroke
				(width 0.1)
				(type default)
			)
			(layer "B.Fab")
		)
		(fp_line
			(start -0.12065 -0.3048)
			(end -0.67945 -0.3048)
			(stroke
				(width 0.1)
				(type default)
			)
			(layer "B.Fab")
		)
		(fp_line
			(start -0.67945 -0.3048)
			(end -0.67945 0.3048)
			(stroke
				(width 0.1)
				(type default)
			)
			(layer "B.Fab")
		)
		(fp_line
			(start 0.12065 -0.2794)
			(end -0.12065 -0.2794)
			(stroke
				(width 0.1)
				(type default)
			)
			(layer "B.Fab")
		)
		(fp_line
			(start -0.12065 -0.2794)
			(end -0.12065 -0.3048)
			(stroke
				(width 0.1)
				(type default)
			)
			(layer "B.Fab")
		)
		(fp_line
			(start 0.12065 0.2794)
			(end 0.12065 0.3048)
			(stroke
				(width 0.1)
				(type default)
			)
			(layer "B.Fab")
		)
		(fp_line
			(start -0.120396 0.2794)
			(end 0.12065 0.2794)
			(stroke
				(width 0.1)
				(type default)
			)
			(layer "B.Fab")
		)
		(fp_line
			(start 0.67945 0.3048)
			(end 0.67945 -0.305054)
			(stroke
				(width 0.1)
				(type default)
			)
			(layer "B.Fab")
		)
		(fp_line
			(start 0.12065 0.3048)
			(end 0.67945 0.3048)
			(stroke
				(width 0.1)
				(type default)
			)
			(layer "B.Fab")
		)
		(fp_line
			(start -0.120396 0.3048)
			(end -0.120396 0.2794)
			(stroke
				(width 0.1)
				(type default)
			)
			(layer "B.Fab")
		)
		(fp_line
			(start -0.67945 0.3048)
			(end -0.120396 0.3048)
			(stroke
				(width 0.1)
				(type default)
			)
			(layer "B.Fab")
		)
		(pad "1" smd circle
			(at 0.40005 0 270)
			(size 0 0)
			(layers "B.Cu" "B.Mask" "B.Paste")
			(net "PVDD11_S3_P1")
		)
		(pad "2" smd circle
			(at -0.40005 0 270)
			(size 0 0)
			(layers "B.Cu" "B.Mask" "B.Paste")
			(net "GND")
		)
	)
	(footprint ""
		(layer "B.Cu")
		(at 105.960164 -255.555242 180)
		(property "Reference" "C3909"
			(at 0 0 0)
			(layer "B.SilkS")
			(hide yes)
			(effects
				(font
					(size 1.27 1.27)
				)
				(justify mirror)
			)
		)
		(property "Value" ""
			(at 0 0 0)
			(layer "B.Fab")
			(effects
				(font
					(size 1.27 1.27)
				)
				(justify mirror)
			)
		)
		(duplicate_pad_numbers_are_jumpers no)
		(fp_line
			(start 0.7874 0.4064)
			(end 0.7874 -0.4064)
			(stroke
				(width 0.1524)
				(type default)
			)
			(layer "B.SilkS")
		)
		(fp_line
			(start 0.7874 -0.4064)
			(end -0.7874 -0.4064)
			(stroke
				(width 0.1524)
				(type default)
			)
			(layer "B.SilkS")
		)
		(fp_line
			(start -0.7874 0.4064)
			(end 0.7874 0.4064)
			(stroke
				(width 0.1524)
				(type default)
			)
			(layer "B.SilkS")
		)
		(fp_line
			(start -0.7874 -0.4064)
			(end -0.7874 0.4064)
			(stroke
				(width 0.1524)
				(type default)
			)
			(layer "B.SilkS")
		)
		(fp_line
			(start 0.67945 0.3048)
			(end 0.67945 -0.305054)
			(stroke
				(width 0.1)
				(type default)
			)
			(layer "B.Fab")
		)
		(fp_line
			(start 0.67945 -0.305054)
			(end 0.12065 -0.305054)
			(stroke
				(width 0.1)
				(type default)
			)
			(layer "B.Fab")
		)
		(fp_line
			(start 0.12065 0.3048)
			(end 0.67945 0.3048)
			(stroke
				(width 0.1)
				(type default)
			)
			(layer "B.Fab")
		)
		(fp_line
			(start 0.12065 0.2794)
			(end 0.12065 0.3048)
			(stroke
				(width 0.1)
				(type default)
			)
			(layer "B.Fab")
		)
		(fp_line
			(start 0.12065 -0.2794)
			(end -0.12065 -0.2794)
			(stroke
				(width 0.1)
				(type default)
			)
			(layer "B.Fab")
		)
		(fp_line
			(start 0.12065 -0.305054)
			(end 0.12065 -0.2794)
			(stroke
				(width 0.1)
				(type default)
			)
			(layer "B.Fab")
		)
		(fp_line
			(start -0.120396 0.3048)
			(end -0.120396 0.2794)
			(stroke
				(width 0.1)
				(type default)
			)
			(layer "B.Fab")
		)
		(fp_line
			(start -0.120396 0.2794)
			(end 0.12065 0.2794)
			(stroke
				(width 0.1)
				(type default)
			)
			(layer "B.Fab")
		)
		(fp_line
			(start -0.12065 -0.2794)
			(end -0.12065 -0.3048)
			(stroke
				(width 0.1)
				(type default)
			)
			(layer "B.Fab")
		)
		(fp_line
			(start -0.12065 -0.3048)
			(end -0.67945 -0.3048)
			(stroke
				(width 0.1)
				(type default)
			)
			(layer "B.Fab")
		)
		(fp_line
			(start -0.67945 0.3048)
			(end -0.120396 0.3048)
			(stroke
				(width 0.1)
				(type default)
			)
			(layer "B.Fab")
		)
		(fp_line
			(start -0.67945 -0.3048)
			(end -0.67945 0.3048)
			(stroke
				(width 0.1)
				(type default)
			)
			(layer "B.Fab")
		)
		(pad "1" smd circle
			(at 0.40005 0)
			(size 0 0)
			(layers "B.Cu" "B.Mask" "B.Paste")
			(net "PVDD18_S5_P1")
		)
		(pad "2" smd circle
			(at -0.40005 0)
			(size 0 0)
			(layers "B.Cu" "B.Mask" "B.Paste")
			(net "GND")
		)
	)
	(footprint ""
		(layer "B.Cu")
		(at 350.723454 -266.00531)
		(property "Reference" "C2629"
			(at 0 0 0)
			(layer "B.SilkS")
			(hide yes)
			(effects
				(font
					(size 1.27 1.27)
				)
				(justify mirror)
			)
		)
		(property "Value" ""
			(at 0 0 0)
			(layer "B.Fab")
			(effects
				(font
					(size 1.27 1.27)
				)
				(justify mirror)
			)
		)
		(duplicate_pad_numbers_are_jumpers no)
		(fp_line
			(start -0.7874 -0.4064)
			(end -0.7874 0.4064)
			(stroke
				(width 0.1524)
				(type default)
			)
			(layer "B.SilkS")
		)
		(fp_line
			(start -0.7874 0.4064)
			(end 0.7874 0.4064)
			(stroke
				(width 0.1524)
				(type default)
			)
			(layer "B.SilkS")
		)
		(fp_line
			(start 0.7874 -0.4064)
			(end -0.7874 -0.4064)
			(stroke
				(width 0.1524)
				(type default)
			)
			(layer "B.SilkS")
		)
		(fp_line
			(start 0.7874 0.4064)
			(end 0.7874 -0.4064)
			(stroke
				(width 0.1524)
				(type default)
			)
			(layer "B.SilkS")
		)
		(fp_line
			(start -0.67945 -0.3048)
			(end -0.67945 0.3048)
			(stroke
				(width 0.1)
				(type default)
			)
			(layer "B.Fab")
		)
		(fp_line
			(start -0.67945 0.3048)
			(end -0.120396 0.3048)
			(stroke
				(width 0.1)
				(type default)
			)
			(layer "B.Fab")
		)
		(fp_line
			(start -0.12065 -0.3048)
			(end -0.67945 -0.3048)
			(stroke
				(width 0.1)
				(type default)
			)
			(layer "B.Fab")
		)
		(fp_line
			(start -0.12065 -0.2794)
			(end -0.12065 -0.3048)
			(stroke
				(width 0.1)
				(type default)
			)
			(layer "B.Fab")
		)
		(fp_line
			(start -0.120396 0.2794)
			(end 0.12065 0.2794)
			(stroke
				(width 0.1)
				(type default)
			)
			(layer "B.Fab")
		)
		(fp_line
			(start -0.120396 0.3048)
			(end -0.120396 0.2794)
			(stroke
				(width 0.1)
				(type default)
			)
			(layer "B.Fab")
		)
		(fp_line
			(start 0.12065 -0.305054)
			(end 0.12065 -0.2794)
			(stroke
				(width 0.1)
				(type default)
			)
			(layer "B.Fab")
		)
		(fp_line
			(start 0.12065 -0.2794)
			(end -0.12065 -0.2794)
			(stroke
				(width 0.1)
				(type default)
			)
			(layer "B.Fab")
		)
		(fp_line
			(start 0.12065 0.2794)
			(end 0.12065 0.3048)
			(stroke
				(width 0.1)
				(type default)
			)
			(layer "B.Fab")
		)
		(fp_line
			(start 0.12065 0.3048)
			(end 0.67945 0.3048)
			(stroke
				(width 0.1)
				(type default)
			)
			(layer "B.Fab")
		)
		(fp_line
			(start 0.67945 -0.305054)
			(end 0.12065 -0.305054)
			(stroke
				(width 0.1)
				(type default)
			)
			(layer "B.Fab")
		)
		(fp_line
			(start 0.67945 0.3048)
			(end 0.67945 -0.305054)
			(stroke
				(width 0.1)
				(type default)
			)
			(layer "B.Fab")
		)
		(pad "1" smd circle
			(at 0.40005 0 180)
			(size 0 0)
			(layers "B.Cu" "B.Mask" "B.Paste")
			(net "PVDD11_S3_P0")
		)
		(pad "2" smd circle
			(at -0.40005 0 180)
			(size 0 0)
			(layers "B.Cu" "B.Mask" "B.Paste")
			(net "GND")
		)
	)
)
